(kicad_pcb
	(version 20260206)
	(generator "pcbnew")
	(generator_version "10.0")
	(general
		(thickness 1.6)
		(legacy_teardrops no)
	)
	(paper "A4")
	(title_block
		(title "Bryce Canyon_Front Panel_16369-1_OCP.brd")
		(comment 1 "Bryce Canyon / footprints 129-132 of 154")
	)
	(layers
		(0 "F.Cu" signal "TOP")
		(4 "In1.Cu" signal "L2GND")
		(6 "In2.Cu" signal "L3VCC")
		(2 "B.Cu" signal "BOTTOM")
		(9 "F.Adhes" user "F.Adhesive")
		(11 "B.Adhes" user "B.Adhesive")
		(13 "F.Paste" user "Package Geometry/Pastemask Top")
		(15 "B.Paste" user "Package Geometry/Pastemask Bottom")
		(5 "F.SilkS" user "Ref Des/Silkscreen Top")
		(7 "B.SilkS" user "Ref Des/Silkscreen Bottom")
		(1 "F.Mask" user "Board Geometry/Soldermask Top")
		(3 "B.Mask" user "Board Geometry/Soldermask Bottom")
		(17 "Dwgs.User" user "User.Drawings")
		(19 "Cmts.User" user "User.Comments")
		(21 "Eco1.User" user "User.Eco1")
		(23 "Eco2.User" user "User.Eco2")
		(25 "Edge.Cuts" user "Board Geometry/Outline")
		(27 "Margin" user)
		(31 "F.CrtYd" user "Package Geometry/Place Bound Top")
		(29 "B.CrtYd" user "Package Geometry/Place Bound Bottom")
		(35 "F.Fab" user "Ref Des/Assembly Top")
		(33 "B.Fab" user "Ref Des/Assembly Bottom")
	)
	(footprint ""
		(layer "F.Cu")
		(at 56.436006 -79.560674 180)
		(property "Reference" "D8"
			(at 0 0 180)
			(layer "F.SilkS")
			(hide yes)
			(effects
				(font
					(size 1.27 1.27)
				)
			)
		)
		(property "Value" "PESD5V0X1UAB-GP"
			(at 0 -4.690618 180)
			(unlocked yes)
			(layer "F.Fab")
			(hide yes)
			(effects
				(font
					(size 1.016 1.016)
					(thickness 0.1524)
				)
			)
		)
		(property "Device Type" "SOD523AKH26"
			(at 0 -6.214618 180)
			(unlocked yes)
			(layer "F.Fab")
			(hide yes)
			(effects
				(font
					(size 1.016 1.016)
					(thickness 0.1524)
				)
			)
		)
		(duplicate_pad_numbers_are_jumpers no)
		(fp_line
			(start 0.5334 1.524)
			(end -0.5334 1.524)
			(stroke
				(width 0.1524)
				(type default)
			)
			(layer "F.SilkS")
		)
		(fp_line
			(start 0.5334 -1.4478)
			(end 0.5334 1.524)
			(stroke
				(width 0.1524)
				(type default)
			)
			(layer "F.SilkS")
		)
		(fp_line
			(start 0.4064 1.651)
			(end -0.4064 1.651)
			(stroke
				(width 0.4064)
				(type default)
			)
			(layer "F.SilkS")
		)
		(fp_line
			(start -0.5334 1.524)
			(end -0.5334 -1.4478)
			(stroke
				(width 0.1524)
				(type default)
			)
			(layer "F.SilkS")
		)
		(fp_line
			(start -0.5334 -1.4478)
			(end 0.5334 -1.4478)
			(stroke
				(width 0.1524)
				(type default)
			)
			(layer "F.SilkS")
		)
		(fp_rect
			(start -0.6096 1.8542)
			(end 0.6096 -1.524)
			(stroke
				(width 0)
				(type default)
			)
			(fill no)
			(layer "F.CrtYd")
		)
		(fp_poly
			(pts
				(xy -0.6096 -1.524) (xy 0.6096 -1.524) (xy 0.6096 1.8542) (xy -0.6096 1.8542)
			)
			(stroke
				(width 0)
				(type default)
			)
			(fill no)
			(layer "F.Fab")
		)
		(pad "A" smd rect
			(at 0 -0.762 180)
			(size 0.5588 1.016)
			(layers "F.Cu" "F.Mask" "F.Paste")
			(net "GND")
		)
		(pad "K" smd rect
			(at 0 0.762 180)
			(size 0.5588 1.016)
			(layers "F.Cu" "F.Mask" "F.Paste")
			(net "PWR_BTN_B")
		)
	)
	(footprint ""
		(layer "F.Cu")
		(at 48.90008 -79.499968)
		(property "Reference" "SW2"
			(at 0 0 0)
			(layer "F.SilkS")
			(hide yes)
			(effects
				(font
					(size 1.27 1.27)
				)
			)
		)
		(property "Value" "SW-TACT-6P-100-GP"
			(at 6.9088 -7.239 0)
			(unlocked yes)
			(layer "F.Fab")
			(hide yes)
			(effects
				(font
					(size 2.54 2.54)
					(thickness 0.381)
				)
			)
		)
		(property "Device Type" "PS004-L22NPR1KKK3UBXX"
			(at 6.9088 -8.763 0)
			(unlocked yes)
			(layer "F.Fab")
			(hide yes)
			(effects
				(font
					(size 2.54 2.54)
					(thickness 0.381)
				)
			)
		)
		(duplicate_pad_numbers_are_jumpers no)
		(fp_line
			(start -5.7912 -0.7874)
			(end -5.198618 -0.7874)
			(stroke
				(width 0.1524)
				(type default)
			)
			(layer "F.SilkS")
		)
		(fp_line
			(start -5.7912 0.7874)
			(end -5.7912 -0.7874)
			(stroke
				(width 0.1524)
				(type default)
			)
			(layer "F.SilkS")
		)
		(fp_line
			(start -5.198618 0.7874)
			(end -5.7912 0.7874)
			(stroke
				(width 0.1524)
				(type default)
			)
			(layer "F.SilkS")
		)
		(fp_line
			(start -4.7498 -4.7498)
			(end -2.254758 -4.7498)
			(stroke
				(width 0.1524)
				(type default)
			)
			(layer "F.SilkS")
		)
		(fp_line
			(start -4.7498 -2.254758)
			(end -4.7498 -4.7498)
			(stroke
				(width 0.1524)
				(type default)
			)
			(layer "F.SilkS")
		)
		(fp_line
			(start -4.7498 4.7498)
			(end -4.7498 2.254758)
			(stroke
				(width 0.1524)
				(type default)
			)
			(layer "F.SilkS")
		)
		(fp_line
			(start -2.254758 4.7498)
			(end -4.7498 4.7498)
			(stroke
				(width 0.1524)
				(type default)
			)
			(layer "F.SilkS")
		)
		(fp_line
			(start 0 -1.0922)
			(end 0 -0.4572)
			(stroke
				(width 0.1524)
				(type default)
			)
			(layer "F.SilkS")
		)
		(fp_line
			(start 2.254758 -4.7498)
			(end 4.7498 -4.7498)
			(stroke
				(width 0.1524)
				(type default)
			)
			(layer "F.SilkS")
		)
		(fp_line
			(start 4.1402 -4.8387)
			(end 4.8387 -4.8387)
			(stroke
				(width 0.3302)
				(type default)
			)
			(layer "F.SilkS")
		)
		(fp_line
			(start 4.7498 -4.7498)
			(end 4.7498 -2.254758)
			(stroke
				(width 0.1524)
				(type default)
			)
			(layer "F.SilkS")
		)
		(fp_line
			(start 4.7498 2.254758)
			(end 4.7498 4.7498)
			(stroke
				(width 0.1524)
				(type default)
			)
			(layer "F.SilkS")
		)
		(fp_line
			(start 4.7498 4.7498)
			(end 2.254758 4.7498)
			(stroke
				(width 0.1524)
				(type default)
			)
			(layer "F.SilkS")
		)
		(fp_line
			(start 4.8387 -4.8387)
			(end 4.8387 -4.1656)
			(stroke
				(width 0.3302)
				(type default)
			)
			(layer "F.SilkS")
		)
		(fp_line
			(start 5.198618 -0.7874)
			(end 5.7912 -0.7874)
			(stroke
				(width 0.1524)
				(type default)
			)
			(layer "F.SilkS")
		)
		(fp_line
			(start 5.7912 -0.7874)
			(end 5.7912 0.7874)
			(stroke
				(width 0.1524)
				(type default)
			)
			(layer "F.SilkS")
		)
		(fp_line
			(start 5.7912 0.7874)
			(end 5.198618 0.7874)
			(stroke
				(width 0.1524)
				(type default)
			)
			(layer "F.SilkS")
		)
		(fp_arc
			(start -5.198618 -0.7874)
			(mid -5.028041 -1.537546)
			(end -4.7498 -2.254758)
			(stroke
				(width 0.1524)
				(type default)
			)
			(layer "F.SilkS")
		)
		(fp_arc
			(start -4.7498 2.254758)
			(mid -5.02801 1.537536)
			(end -5.198618 0.7874)
			(stroke
				(width 0.1524)
				(type default)
			)
			(layer "F.SilkS")
		)
		(fp_arc
			(start -2.254758 -4.7498)
			(mid 0 -5.257807)
			(end 2.254758 -4.7498)
			(stroke
				(width 0.1524)
				(type default)
			)
			(layer "F.SilkS")
		)
		(fp_arc
			(start 0 1.016)
			(mid -0.938662 0.388806)
			(end -0.718312 -0.718312)
			(stroke
				(width 0.1524)
				(type default)
			)
			(layer "F.SilkS")
		)
		(fp_arc
			(start 0.718312 -0.718312)
			(mid 0.93852 0.388748)
			(end 0 1.016)
			(stroke
				(width 0.1524)
				(type default)
			)
			(layer "F.SilkS")
		)
		(fp_arc
			(start 2.254758 4.7498)
			(mid 0 5.257807)
			(end -2.254758 4.7498)
			(stroke
				(width 0.1524)
				(type default)
			)
			(layer "F.SilkS")
		)
		(fp_arc
			(start 4.7498 -2.254758)
			(mid 5.02801 -1.537536)
			(end 5.198618 -0.7874)
			(stroke
				(width 0.1524)
				(type default)
			)
			(layer "F.SilkS")
		)
		(fp_arc
			(start 5.198618 0.7874)
			(mid 5.028041 1.537546)
			(end 4.7498 2.254758)
			(stroke
				(width 0.1524)
				(type default)
			)
			(layer "F.SilkS")
		)
		(fp_circle
			(center -4.99999 0)
			(end -4.11099 0)
			(stroke
				(width 0.3048)
				(type default)
			)
			(fill no)
			(layer "F.SilkS")
		)
		(fp_circle
			(center -2.500122 -2.500122)
			(end -1.484122 -2.500122)
			(stroke
				(width 0.3048)
				(type default)
			)
			(fill no)
			(layer "F.SilkS")
		)
		(fp_circle
			(center -2.500122 2.500122)
			(end -1.484122 2.500122)
			(stroke
				(width 0.3048)
				(type default)
			)
			(fill no)
			(layer "F.SilkS")
		)
		(fp_circle
			(center 0 -2.500122)
			(end 1.016 -2.500122)
			(stroke
				(width 0.3048)
				(type default)
			)
			(fill no)
			(layer "F.SilkS")
		)
		(fp_circle
			(center 0 2.500122)
			(end 1.016 2.500122)
			(stroke
				(width 0.3048)
				(type default)
			)
			(fill no)
			(layer "F.SilkS")
		)
		(fp_circle
			(center 2.500122 -2.500122)
			(end 3.516122 -2.500122)
			(stroke
				(width 0.3048)
				(type default)
			)
			(fill no)
			(layer "F.SilkS")
		)
		(fp_circle
			(center 2.500122 2.500122)
			(end 3.516122 2.500122)
			(stroke
				(width 0.3048)
				(type default)
			)
			(fill no)
			(layer "F.SilkS")
		)
		(fp_circle
			(center 4.99999 0)
			(end 5.88899 0)
			(stroke
				(width 0.3048)
				(type default)
			)
			(fill no)
			(layer "F.SilkS")
		)
		(fp_poly
			(pts
				(arc
					(start 2.196846 4.4958)
					(mid 0 5.003834)
					(end -2.196846 4.4958)
				)
				(xy -4.4958 4.4958)
				(arc
					(start -4.4958 2.196846)
					(mid -4.845024 1.250828)
					(end -4.99745 0.254)
				)
				(xy -5.1308 0.254) (xy -5.1308 -0.254)
				(arc
					(start -4.99745 -0.254)
					(mid -4.844994 -1.250821)
					(end -4.4958 -2.196846)
				)
				(xy -4.4958 -4.4958)
				(arc
					(start -2.196846 -4.4958)
					(mid 0 -5.003834)
					(end 2.196846 -4.4958)
				)
				(xy 4.4958 -4.4958)
				(arc
					(start 4.4958 -2.196846)
					(mid 4.845024 -1.250828)
					(end 4.99745 -0.254)
				)
				(xy 5.1308 -0.254) (xy 5.1308 0.254)
				(arc
					(start 4.99745 0.254)
					(mid 4.844994 1.250821)
					(end 4.4958 2.196846)
				)
				(xy 4.4958 4.4958)
			)
			(stroke
				(width 0)
				(type default)
			)
			(fill no)
			(layer "F.CrtYd")
		)
		(fp_poly
			(pts
				(arc
					(start 2.3114 5.0038)
					(mid 0 5.511859)
					(end -2.3114 5.0038)
				)
				(xy -5.0038 5.0038)
				(arc
					(start -5.0038 2.3114)
					(mid -5.246729 1.688816)
					(end -5.412486 1.0414)
				)
				(xy -6.0452 1.0414) (xy -6.0452 -1.0414)
				(arc
					(start -5.412486 -1.0414)
					(mid -5.246693 -1.688804)
					(end -5.0038 -2.3114)
				)
				(xy -5.0038 -5.0038)
				(arc
					(start -2.3114 -5.0038)
					(mid 0 -5.511859)
					(end 2.3114 -5.0038)
				)
				(xy 5.0038 -5.0038)
				(arc
					(start 5.0038 -2.3114)
					(mid 5.246729 -1.688816)
					(end 5.412486 -1.0414)
				)
				(xy 6.0452 -1.0414) (xy 6.0452 -0.00635) (xy 5.1308 -0.00635) (xy 5.1308 -0.254)
				(arc
					(start 4.997704 -0.254)
					(mid 4.845133 -1.250792)
					(end 4.496054 -2.196846)
				)
				(xy 4.4958 -4.4958)
				(arc
					(start 2.196846 -4.4958)
					(mid 0 -5.003834)
					(end -2.196846 -4.4958)
				)
				(xy -4.4958 -4.4958)
				(arc
					(start -4.4958 -2.196846)
					(mid -4.84509 -1.250826)
					(end -4.997704 -0.254)
				)
				(xy -5.1308 -0.254) (xy -5.1308 0.254)
				(arc
					(start -4.997704 0.254)
					(mid -4.845193 1.250762)
					(end -4.496308 2.196846)
				)
				(xy -4.4958 4.4958)
				(arc
					(start -2.196846 4.4958)
					(mid 0 5.003834)
					(end 2.196846 4.4958)
				)
				(xy 4.4958 4.4958)
				(arc
					(start 4.4958 2.196846)
					(mid 4.84509 1.250826)
					(end 4.997704 0.254)
				)
				(xy 5.1308 0.254) (xy 5.1308 0.00635) (xy 6.0452 0.00635) (xy 6.0452 1.0414)
				(arc
					(start 5.412486 1.0414)
					(mid 5.246693 1.688804)
					(end 5.0038 2.3114)
				)
				(xy 5.0038 5.0038)
			)
			(stroke
				(width 0)
				(type default)
			)
			(fill no)
			(layer "F.CrtYd")
		)
		(fp_poly
			(pts
				(arc
					(start 2.3114 5.0038)
					(mid 0 5.511859)
					(end -2.3114 5.0038)
				)
				(xy -5.0038 5.0038)
				(arc
					(start -5.0038 2.3114)
					(mid -5.246729 1.688816)
					(end -5.412486 1.0414)
				)
				(xy -6.0452 1.0414) (xy -6.0452 -1.0414)
				(arc
					(start -5.412486 -1.0414)
					(mid -5.246693 -1.688804)
					(end -5.0038 -2.3114)
				)
				(xy -5.0038 -5.0038)
				(arc
					(start -2.3114 -5.0038)
					(mid 0 -5.511859)
					(end 2.3114 -5.0038)
				)
				(xy 5.0038 -5.0038)
				(arc
					(start 5.0038 -2.3114)
					(mid 5.246729 -1.688816)
					(end 5.412486 -1.0414)
				)
				(xy 6.0452 -1.0414) (xy 6.0452 1.0414)
				(arc
					(start 5.412486 1.0414)
					(mid 5.246693 1.688804)
					(end 5.0038 2.3114)
				)
				(xy 5.0038 5.0038)
			)
			(stroke
				(width 0)
				(type default)
			)
			(fill no)
			(layer "F.Fab")
		)
		(pad "1" thru_hole circle
			(at 2.500122 -2.500122)
			(size 1.3208 1.3208)
			(drill 0.9144)
			(layers "*.Cu" "*.Mask")
			(remove_unused_layers no)
			(net "PWR_BTN_B")
			(clearance 0.1524)
			(thermal_gap 0.1524)
		)
		(pad "2" thru_hole circle
			(at 0 -2.500122)
			(size 1.3208 1.3208)
			(drill 0.9144)
			(layers "*.Cu" "*.Mask")
			(remove_unused_layers no)
			(net "PWR_BTN_B_CONN")
			(clearance 0.1524)
			(thermal_gap 0.1524)
		)
		(pad "3" thru_hole circle
			(at -2.500122 -2.500122)
			(size 1.3208 1.3208)
			(drill 0.9144)
			(layers "*.Cu" "*.Mask")
			(remove_unused_layers no)
			(net "Net_81")
			(clearance 0.1524)
			(thermal_gap 0.1524)
		)
		(pad "4" thru_hole circle
			(at 2.500122 2.500122)
			(size 1.3208 1.3208)
			(drill 0.9144)
			(layers "*.Cu" "*.Mask")
			(remove_unused_layers no)
			(net "GND")
			(clearance 0.1524)
			(thermal_gap 0.1524)
		)
		(pad "5" thru_hole circle
			(at 0 2.500122)
			(size 1.3208 1.3208)
			(drill 0.9144)
			(layers "*.Cu" "*.Mask")
			(remove_unused_layers no)
			(net "PWR_BTN_B_CONN")
			(clearance 0.1524)
			(thermal_gap 0.1524)
		)
		(pad "6" thru_hole circle
			(at -2.500122 2.500122)
			(size 1.3208 1.3208)
			(drill 0.9144)
			(layers "*.Cu" "*.Mask")
			(remove_unused_layers no)
			(net "Net_82")
			(clearance 0.1524)
			(thermal_gap 0.1524)
		)
		(pad "L1" thru_hole circle
			(at 4.99999 0)
			(size 1.0668 1.0668)
			(drill 0.7112)
			(layers "*.Cu" "*.Mask")
			(remove_unused_layers no)
			(net "PWR_BTN_LED_B_R")
			(clearance 0.1778)
			(thermal_gap 0.1778)
		)
		(pad "L2" thru_hole circle
			(at -4.99999 0)
			(size 1.0668 1.0668)
			(drill 0.7112)
			(layers "*.Cu" "*.Mask")
			(remove_unused_layers no)
			(net "PWR_LED_B_N")
			(clearance 0.1778)
			(thermal_gap 0.1778)
		)
	)
	(footprint ""
		(layer "F.Cu")
		(at 9.9568 -12.3444 -90)
		(property "Reference" "C1"
			(at 0 0 270)
			(layer "F.SilkS")
			(hide yes)
			(effects
				(font
					(size 1.27 1.27)
				)
			)
		)
		(property "Value" "SCD1U16V2KX-3GP"
			(at 1.1811 -3.3909 270)
			(unlocked yes)
			(layer "F.Fab")
			(hide yes)
			(effects
				(font
					(size 2.54 2.54)
					(thickness 0.381)
				)
			)
		)
		(property "Device Type" "C402H22"
			(at 1.1811 -4.9149 270)
			(unlocked yes)
			(layer "F.Fab")
			(hide yes)
			(effects
				(font
					(size 2.54 2.54)
					(thickness 0.381)
				)
			)
		)
		(duplicate_pad_numbers_are_jumpers no)
		(fp_rect
			(start -0.4318 0.9525)
			(end 0.4318 -0.9525)
			(stroke
				(width 0)
				(type default)
			)
			(fill no)
			(layer "F.CrtYd")
		)
		(fp_rect
			(start -0.4318 0.9525)
			(end 0.4318 -0.9525)
			(stroke
				(width 0)
				(type default)
			)
			(fill no)
			(layer "F.Fab")
		)
		(pad "1" smd custom
			(at 0 -0.4445 270)
			(size 0.1524 0.1524)
			(layers "F.Cu" "F.Mask" "F.Paste")
			(net "P3V3_STBY_A")
			(options
				(clearance outline)
				(anchor circle)
			)
			(primitives
				(gr_poly
					(pts
						(arc
							(start 0.3048 -0.2032)
							(mid 0.275042 -0.275042)
							(end 0.2032 -0.3048)
						)
						(arc
							(start -0.2032 -0.3048)
							(mid -0.275042 -0.275042)
							(end -0.3048 -0.2032)
						)
						(arc
							(start -0.3048 0.2032)
							(mid -0.275042 0.275042)
							(end -0.2032 0.3048)
						)
						(arc
							(start 0.2032 0.3048)
							(mid 0.275042 0.275042)
							(end 0.3048 0.2032)
						)
					)
					(width 0)
					(fill yes)
				)
			)
		)
		(pad "2" smd custom
			(at 0 0.4445 270)
			(size 0.1524 0.1524)
			(layers "F.Cu" "F.Mask" "F.Paste")
			(net "GND")
			(options
				(clearance outline)
				(anchor circle)
			)
			(primitives
				(gr_poly
					(pts
						(arc
							(start 0.3048 -0.2032)
							(mid 0.275042 -0.275042)
							(end 0.2032 -0.3048)
						)
						(arc
							(start -0.2032 -0.3048)
							(mid -0.275042 -0.275042)
							(end -0.3048 -0.2032)
						)
						(arc
							(start -0.3048 0.2032)
							(mid -0.275042 0.275042)
							(end -0.2032 0.3048)
						)
						(arc
							(start 0.2032 0.3048)
							(mid 0.275042 0.275042)
							(end 0.3048 0.2032)
						)
					)
					(width 0)
					(fill yes)
				)
			)
		)
	)
	(footprint ""
		(layer "F.Cu")
		(at 45.400214 -72.186546 180)
		(property "Reference" "D4"
			(at 0 0 180)
			(layer "F.SilkS")
			(hide yes)
			(effects
				(font
					(size 1.27 1.27)
				)
			)
		)
		(property "Value" "PESD5V0S1BL-1-GP"
			(at 1.8923 -1.5621 180)
			(unlocked yes)
			(layer "F.Fab")
			(hide yes)
			(effects
				(font
					(size 1.016 1.016)
					(thickness 0.1524)
				)
			)
		)
		(property "Device Type" "SOD882-10D6-1H20"
			(at 1.8923 -3.0861 180)
			(unlocked yes)
			(layer "F.Fab")
			(hide yes)
			(effects
				(font
					(size 1.016 1.016)
					(thickness 0.1524)
				)
			)
		)
		(duplicate_pad_numbers_are_jumpers no)
		(fp_line
			(start -0.3048 -0.9271)
			(end 0.3048 -0.9271)
			(stroke
				(width 0.254)
				(type default)
			)
			(layer "F.SilkS")
		)
		(fp_rect
			(start -0.2921 0.4953)
			(end 0.2921 -0.4953)
			(stroke
				(width 0)
				(type default)
			)
			(fill no)
			(layer "F.CrtYd")
		)
		(fp_poly
			(pts
				(xy -0.4318 0.8001) (xy -0.4318 -0.266192) (xy -0.2921 -0.266192) (xy -0.2921 0.4953) (xy 0.2921 0.4953)
				(xy 0.2921 -0.4953) (xy -0.2921 -0.4953) (xy -0.2921 -0.2667) (xy -0.4318 -0.2667) (xy -0.4318 -0.8001)
				(xy 0.4318 -0.8001) (xy 0.4318 0.8001)
			)
			(stroke
				(width 0)
				(type default)
			)
			(fill no)
			(layer "F.CrtYd")
		)
		(fp_rect
			(start -0.4318 0.8001)
			(end 0.4318 -0.8001)
			(stroke
				(width 0)
				(type default)
			)
			(fill no)
			(layer "F.Fab")
		)
		(pad "1" smd custom
			(at 0 -0.4445 180)
			(size 0.1143 0.1143)
			(layers "F.Cu" "F.Mask" "F.Paste")
			(net "P5V_VBUS_B")
			(options
				(clearance outline)
				(anchor circle)
			)
			(primitives
				(gr_poly
					(pts
						(arc
							(start -0.2032 0.2286)
							(mid -0.275042 0.198842)
							(end -0.3048 0.127)
						)
						(arc
							(start -0.3048 -0.127)
							(mid -0.275042 -0.198842)
							(end -0.2032 -0.2286)
						)
						(arc
							(start 0.2032 -0.2286)
							(mid 0.275042 -0.198842)
							(end 0.3048 -0.127)
						)
						(arc
							(start 0.3048 0.127)
							(mid 0.275042 0.198842)
							(end 0.2032 0.2286)
						)
					)
					(width 0)
					(fill yes)
				)
			)
		)
		(pad "2" smd custom
			(at 0 0.4445 180)
			(size 0.1143 0.1143)
			(layers "F.Cu" "F.Mask" "F.Paste")
			(net "GND")
			(options
				(clearance outline)
				(anchor circle)
			)
			(primitives
				(gr_poly
					(pts
						(arc
							(start 0.2032 -0.2286)
							(mid 0.275042 -0.198842)
							(end 0.3048 -0.127)
						)
						(arc
							(start 0.3048 0.127)
							(mid 0.275042 0.198842)
							(end 0.2032 0.2286)
						)
						(arc
							(start -0.2032 0.2286)
							(mid -0.275042 0.198842)
							(end -0.3048 0.127)
						)
						(arc
							(start -0.3048 -0.127)
							(mid -0.275042 -0.198842)
							(end -0.2032 -0.2286)
						)
					)
					(width 0)
					(fill yes)
				)
			)
		)
	)
)
